(kicad_pcb
	(version 20260206)
	(generator "pcbnew")
	(generator_version "10.0")
	(general
		(thickness 1.6)
		(legacy_teardrops no)
	)
	(paper "A4")
	(title_block
		(title "04192023_DAF0TMB3IC0_F0TG_MB_C_brd_V02_OCP.brd")
		(comment 1 "Grand Teton / footprints 539-545 of 8354")
	)
	(layers
		(0 "F.Cu" signal "TOP")
		(4 "In1.Cu" signal "GND")
		(6 "In2.Cu" signal "IN1")
		(8 "In3.Cu" signal "GND1")
		(10 "In4.Cu" signal "IN2")
		(12 "In5.Cu" signal "GND2")
		(14 "In6.Cu" signal "IN3")
		(16 "In7.Cu" signal "GND3")
		(18 "In8.Cu" signal "VCC")
		(20 "In9.Cu" signal "VCC1")
		(22 "In10.Cu" signal "GND4")
		(24 "In11.Cu" signal "IN4")
		(26 "In12.Cu" signal "GND5")
		(28 "In13.Cu" signal "IN5")
		(30 "In14.Cu" signal "GND6")
		(32 "In15.Cu" signal "IN6")
		(34 "In16.Cu" signal "GND7")
		(2 "B.Cu" signal "BOTTOM")
		(9 "F.Adhes" user "F.Adhesive")
		(11 "B.Adhes" user "B.Adhesive")
		(13 "F.Paste" user "Package Geometry/Pastemask Top")
		(15 "B.Paste" user "Package Geometry/Pastemask Bottom")
		(5 "F.SilkS" user "Ref Des/Silkscreen Top")
		(7 "B.SilkS" user "Ref Des/Silkscreen Bottom")
		(1 "F.Mask" user "Board Geometry/Soldermask Top")
		(3 "B.Mask" user "Board Geometry/Soldermask Bottom")
		(17 "Dwgs.User" user "User.Drawings")
		(19 "Cmts.User" user "User.Comments")
		(21 "Eco1.User" user "User.Eco1")
		(23 "Eco2.User" user "User.Eco2")
		(25 "Edge.Cuts" user "Board Geometry/Outline")
		(27 "Margin" user)
		(31 "F.CrtYd" user "Package Geometry/Place Bound Top")
		(29 "B.CrtYd" user "Package Geometry/Place Bound Bottom")
		(35 "F.Fab" user "Ref Des/Assembly Top")
		(33 "B.Fab" user "Ref Des/Assembly Bottom")
	)
	(footprint ""
		(layer "F.Cu")
		(at 208.892394 -107.467146)
		(property "Reference" "C8005"
			(at 0 0 0)
			(layer "F.SilkS")
			(hide yes)
			(effects
				(font
					(size 1.27 1.27)
				)
			)
		)
		(property "Value" ""
			(at 0 0 0)
			(layer "F.Fab")
			(effects
				(font
					(size 1.27 1.27)
				)
			)
		)
		(duplicate_pad_numbers_are_jumpers no)
		(fp_line
			(start -0.7874 -0.4064)
			(end 0.7874 -0.4064)
			(stroke
				(width 0.1524)
				(type default)
			)
			(layer "F.SilkS")
		)
		(fp_line
			(start -0.7874 0.4064)
			(end -0.7874 -0.4064)
			(stroke
				(width 0.1524)
				(type default)
			)
			(layer "F.SilkS")
		)
		(fp_line
			(start 0.7874 -0.4064)
			(end 0.7874 0.4064)
			(stroke
				(width 0.1524)
				(type default)
			)
			(layer "F.SilkS")
		)
		(fp_line
			(start 0.7874 0.4064)
			(end -0.7874 0.4064)
			(stroke
				(width 0.1524)
				(type default)
			)
			(layer "F.SilkS")
		)
		(fp_line
			(start -0.67945 -0.305054)
			(end -0.12065 -0.305054)
			(stroke
				(width 0.1)
				(type default)
			)
			(layer "F.Fab")
		)
		(fp_line
			(start -0.67945 0.3048)
			(end -0.67945 -0.305054)
			(stroke
				(width 0.1)
				(type default)
			)
			(layer "F.Fab")
		)
		(fp_line
			(start -0.12065 -0.305054)
			(end -0.12065 -0.2794)
			(stroke
				(width 0.1)
				(type default)
			)
			(layer "F.Fab")
		)
		(fp_line
			(start -0.12065 -0.2794)
			(end 0.12065 -0.2794)
			(stroke
				(width 0.1)
				(type default)
			)
			(layer "F.Fab")
		)
		(fp_line
			(start -0.12065 0.2794)
			(end -0.12065 0.3048)
			(stroke
				(width 0.1)
				(type default)
			)
			(layer "F.Fab")
		)
		(fp_line
			(start -0.12065 0.3048)
			(end -0.67945 0.3048)
			(stroke
				(width 0.1)
				(type default)
			)
			(layer "F.Fab")
		)
		(fp_line
			(start 0.120396 0.2794)
			(end -0.12065 0.2794)
			(stroke
				(width 0.1)
				(type default)
			)
			(layer "F.Fab")
		)
		(fp_line
			(start 0.120396 0.3048)
			(end 0.120396 0.2794)
			(stroke
				(width 0.1)
				(type default)
			)
			(layer "F.Fab")
		)
		(fp_line
			(start 0.12065 -0.3048)
			(end 0.67945 -0.3048)
			(stroke
				(width 0.1)
				(type default)
			)
			(layer "F.Fab")
		)
		(fp_line
			(start 0.12065 -0.2794)
			(end 0.12065 -0.3048)
			(stroke
				(width 0.1)
				(type default)
			)
			(layer "F.Fab")
		)
		(fp_line
			(start 0.67945 -0.3048)
			(end 0.67945 0.3048)
			(stroke
				(width 0.1)
				(type default)
			)
			(layer "F.Fab")
		)
		(fp_line
			(start 0.67945 0.3048)
			(end 0.120396 0.3048)
			(stroke
				(width 0.1)
				(type default)
			)
			(layer "F.Fab")
		)
		(pad "1" smd circle
			(at -0.40005 0)
			(size 0 0)
			(layers "F.Cu" "F.Mask" "F.Paste")
			(net "PWRGD_P5V_AUX_R3")
		)
		(pad "2" smd circle
			(at 0.40005 0)
			(size 0 0)
			(layers "F.Cu" "F.Mask" "F.Paste")
			(net "GND")
		)
	)
	(footprint ""
		(layer "F.Cu")
		(at 96.0628 -418.0332 180)
		(property "Reference" "R1456"
			(at 0 0 180)
			(layer "F.SilkS")
			(hide yes)
			(effects
				(font
					(size 1.27 1.27)
				)
			)
		)
		(property "Value" ""
			(at 0 0 180)
			(layer "F.Fab")
			(effects
				(font
					(size 1.27 1.27)
				)
			)
		)
		(duplicate_pad_numbers_are_jumpers no)
		(fp_line
			(start 0.32512 0.175006)
			(end -0.32512 0.175006)
			(stroke
				(width 0.1)
				(type default)
			)
			(layer "F.Fab")
		)
		(fp_line
			(start 0.32512 -0.175006)
			(end 0.32512 0.175006)
			(stroke
				(width 0.1)
				(type default)
			)
			(layer "F.Fab")
		)
		(fp_line
			(start -0.32512 0.175006)
			(end -0.32512 -0.175006)
			(stroke
				(width 0.1)
				(type default)
			)
			(layer "F.Fab")
		)
		(fp_line
			(start -0.32512 -0.175006)
			(end 0.32512 -0.175006)
			(stroke
				(width 0.1)
				(type default)
			)
			(layer "F.Fab")
		)
		(pad "1" smd rect
			(at -0.2667 0 180)
			(size 0.3048 0.381)
			(layers "F.Cu" "F.Mask" "F.Paste")
			(net "P1V8_CPU1_RT_1D")
		)
		(pad "2" smd rect
			(at 0.2667 0)
			(size 0.3048 0.381)
			(layers "F.Cu" "F.Mask" "F.Paste")
			(net "JTAG_TDO_RT_CPU1_P1")
		)
	)
	(footprint ""
		(layer "F.Cu")
		(at 149.230334 -191.371982 -90)
		(property "Reference" "R3197"
			(at 0 0 270)
			(layer "F.SilkS")
			(hide yes)
			(effects
				(font
					(size 1.27 1.27)
				)
			)
		)
		(property "Value" ""
			(at 0 0 270)
			(layer "F.Fab")
			(effects
				(font
					(size 1.27 1.27)
				)
			)
		)
		(duplicate_pad_numbers_are_jumpers no)
		(fp_line
			(start -0.7874 0.4064)
			(end -0.7874 0.056134)
			(stroke
				(width 0.1524)
				(type default)
			)
			(layer "F.SilkS")
		)
		(fp_line
			(start 0.7874 0.4064)
			(end -0.7874 0.4064)
			(stroke
				(width 0.1524)
				(type default)
			)
			(layer "F.SilkS")
		)
		(fp_line
			(start 0.7874 -0.045466)
			(end 0.7874 0.4064)
			(stroke
				(width 0.1524)
				(type default)
			)
			(layer "F.SilkS")
		)
		(fp_line
			(start -0.347218 -0.4064)
			(end 0.440182 -0.4064)
			(stroke
				(width 0.1524)
				(type default)
			)
			(layer "F.SilkS")
		)
		(fp_line
			(start -0.67945 0.3048)
			(end -0.67945 -0.305054)
			(stroke
				(width 0.1)
				(type default)
			)
			(layer "F.Fab")
		)
		(fp_line
			(start -0.12065 0.3048)
			(end -0.67945 0.3048)
			(stroke
				(width 0.1)
				(type default)
			)
			(layer "F.Fab")
		)
		(fp_line
			(start 0.120396 0.3048)
			(end 0.120396 0.2794)
			(stroke
				(width 0.1)
				(type default)
			)
			(layer "F.Fab")
		)
		(fp_line
			(start 0.67945 0.3048)
			(end 0.120396 0.3048)
			(stroke
				(width 0.1)
				(type default)
			)
			(layer "F.Fab")
		)
		(fp_line
			(start -0.12065 0.2794)
			(end -0.12065 0.3048)
			(stroke
				(width 0.1)
				(type default)
			)
			(layer "F.Fab")
		)
		(fp_line
			(start 0.120396 0.2794)
			(end -0.12065 0.2794)
			(stroke
				(width 0.1)
				(type default)
			)
			(layer "F.Fab")
		)
		(fp_line
			(start -0.12065 -0.2794)
			(end 0.12065 -0.2794)
			(stroke
				(width 0.1)
				(type default)
			)
			(layer "F.Fab")
		)
		(fp_line
			(start 0.12065 -0.2794)
			(end 0.12065 -0.3048)
			(stroke
				(width 0.1)
				(type default)
			)
			(layer "F.Fab")
		)
		(fp_line
			(start 0.12065 -0.3048)
			(end 0.67945 -0.3048)
			(stroke
				(width 0.1)
				(type default)
			)
			(layer "F.Fab")
		)
		(fp_line
			(start 0.67945 -0.3048)
			(end 0.67945 0.3048)
			(stroke
				(width 0.1)
				(type default)
			)
			(layer "F.Fab")
		)
		(fp_line
			(start -0.67945 -0.305054)
			(end -0.12065 -0.305054)
			(stroke
				(width 0.1)
				(type default)
			)
			(layer "F.Fab")
		)
		(fp_line
			(start -0.12065 -0.305054)
			(end -0.12065 -0.2794)
			(stroke
				(width 0.1)
				(type default)
			)
			(layer "F.Fab")
		)
		(pad "1" smd circle
			(at -0.40005 0 270)
			(size 0 0)
			(layers "F.Cu" "F.Mask" "F.Paste")
			(net "CLK_100M_CPU1_CLK03_R_DN")
		)
		(pad "2" smd circle
			(at 0.40005 0 270)
			(size 0 0)
			(layers "F.Cu" "F.Mask" "F.Paste")
			(net "CLK_100M_CPU1_CLK03_DN")
		)
	)
	(footprint ""
		(layer "F.Cu")
		(at 399.197322 -134.92988)
		(property "Reference" "R2344"
			(at 0 0 0)
			(layer "F.SilkS")
			(hide yes)
			(effects
				(font
					(size 1.27 1.27)
				)
			)
		)
		(property "Value" ""
			(at 0 0 0)
			(layer "F.Fab")
			(effects
				(font
					(size 1.27 1.27)
				)
			)
		)
		(duplicate_pad_numbers_are_jumpers no)
		(fp_line
			(start -0.7874 -0.4064)
			(end 0.7874 -0.4064)
			(stroke
				(width 0.1524)
				(type default)
			)
			(layer "F.SilkS")
		)
		(fp_line
			(start -0.7874 0.4064)
			(end -0.7874 -0.4064)
			(stroke
				(width 0.1524)
				(type default)
			)
			(layer "F.SilkS")
		)
		(fp_line
			(start 0.7874 -0.4064)
			(end 0.7874 0.4064)
			(stroke
				(width 0.1524)
				(type default)
			)
			(layer "F.SilkS")
		)
		(fp_line
			(start 0.7874 0.4064)
			(end -0.7874 0.4064)
			(stroke
				(width 0.1524)
				(type default)
			)
			(layer "F.SilkS")
		)
		(fp_line
			(start -0.67945 -0.305054)
			(end -0.12065 -0.305054)
			(stroke
				(width 0.1)
				(type default)
			)
			(layer "F.Fab")
		)
		(fp_line
			(start -0.67945 0.3048)
			(end -0.67945 -0.305054)
			(stroke
				(width 0.1)
				(type default)
			)
			(layer "F.Fab")
		)
		(fp_line
			(start -0.12065 -0.305054)
			(end -0.12065 -0.2794)
			(stroke
				(width 0.1)
				(type default)
			)
			(layer "F.Fab")
		)
		(fp_line
			(start -0.12065 -0.2794)
			(end 0.12065 -0.2794)
			(stroke
				(width 0.1)
				(type default)
			)
			(layer "F.Fab")
		)
		(fp_line
			(start -0.12065 0.2794)
			(end -0.12065 0.3048)
			(stroke
				(width 0.1)
				(type default)
			)
			(layer "F.Fab")
		)
		(fp_line
			(start -0.12065 0.3048)
			(end -0.67945 0.3048)
			(stroke
				(width 0.1)
				(type default)
			)
			(layer "F.Fab")
		)
		(fp_line
			(start 0.120396 0.2794)
			(end -0.12065 0.2794)
			(stroke
				(width 0.1)
				(type default)
			)
			(layer "F.Fab")
		)
		(fp_line
			(start 0.120396 0.3048)
			(end 0.120396 0.2794)
			(stroke
				(width 0.1)
				(type default)
			)
			(layer "F.Fab")
		)
		(fp_line
			(start 0.12065 -0.3048)
			(end 0.67945 -0.3048)
			(stroke
				(width 0.1)
				(type default)
			)
			(layer "F.Fab")
		)
		(fp_line
			(start 0.12065 -0.2794)
			(end 0.12065 -0.3048)
			(stroke
				(width 0.1)
				(type default)
			)
			(layer "F.Fab")
		)
		(fp_line
			(start 0.67945 -0.3048)
			(end 0.67945 0.3048)
			(stroke
				(width 0.1)
				(type default)
			)
			(layer "F.Fab")
		)
		(fp_line
			(start 0.67945 0.3048)
			(end 0.120396 0.3048)
			(stroke
				(width 0.1)
				(type default)
			)
			(layer "F.Fab")
		)
		(pad "1" smd circle
			(at -0.40005 0)
			(size 0 0)
			(layers "F.Cu" "F.Mask" "F.Paste")
			(net "P3V3_AUX")
		)
		(pad "2" smd circle
			(at 0.40005 0)
			(size 0 0)
			(layers "F.Cu" "F.Mask" "F.Paste")
			(net "PWRGD_P5V_AUX_R1")
		)
	)
	(footprint ""
		(layer "F.Cu")
		(at 423.35704 -439.284872)
		(property "Reference" "Q69"
			(at -1.239266 -1.871726 0)
			(unlocked yes)
			(layer "F.SilkS")
			(effects
				(font
					(size 0.7874 0.5842)
					(thickness 0.1524)
				)
				(justify left)
			)
		)
		(property "Value" ""
			(at 0 0 0)
			(layer "F.Fab")
			(effects
				(font
					(size 1.27 1.27)
				)
			)
		)
		(duplicate_pad_numbers_are_jumpers no)
		(fp_line
			(start -1.332738 -1.100074)
			(end -0.4826 -1.100074)
			(stroke
				(width 0.1524)
				(type default)
			)
			(layer "F.SilkS")
		)
		(fp_line
			(start -1.332738 1.100074)
			(end -1.332738 -1.100074)
			(stroke
				(width 0.1524)
				(type default)
			)
			(layer "F.SilkS")
		)
		(fp_line
			(start -0.4826 -1.100074)
			(end 0 -0.541274)
			(stroke
				(width 0.1524)
				(type default)
			)
			(layer "F.SilkS")
		)
		(fp_line
			(start 0 -0.541274)
			(end 0.4826 -1.100074)
			(stroke
				(width 0.1524)
				(type default)
			)
			(layer "F.SilkS")
		)
		(fp_line
			(start 0.4826 -1.100074)
			(end 1.332738 -1.100074)
			(stroke
				(width 0.1524)
				(type default)
			)
			(layer "F.SilkS")
		)
		(fp_line
			(start 1.332738 -1.100074)
			(end 1.332738 1.100074)
			(stroke
				(width 0.1524)
				(type default)
			)
			(layer "F.SilkS")
		)
		(fp_line
			(start 1.332738 1.100074)
			(end -1.332738 1.100074)
			(stroke
				(width 0.1524)
				(type default)
			)
			(layer "F.SilkS")
		)
		(fp_poly
			(pts
				(xy -1.533144 -0.649986) (xy -2.2352 -0.298958) (xy -2.2352 -1.001014)
			)
			(stroke
				(width 0)
				(type default)
			)
			(fill yes)
			(layer "F.SilkS")
		)
		(fp_line
			(start -0.674878 -1.100074)
			(end 0.674878 -1.100074)
			(stroke
				(width 0.1)
				(type default)
			)
			(layer "F.Fab")
		)
		(fp_line
			(start -0.674878 1.100074)
			(end -0.674878 -1.100074)
			(stroke
				(width 0.1)
				(type default)
			)
			(layer "F.Fab")
		)
		(fp_line
			(start 0.674878 -1.100074)
			(end 0.674878 1.100074)
			(stroke
				(width 0.1)
				(type default)
			)
			(layer "F.Fab")
		)
		(fp_line
			(start 0.674878 1.100074)
			(end -0.674878 1.100074)
			(stroke
				(width 0.1)
				(type default)
			)
			(layer "F.Fab")
		)
		(fp_poly
			(pts
				(xy -2.2352 -0.298958) (xy -2.2352 -1.001014) (xy -1.533144 -0.649986)
			)
			(stroke
				(width 0)
				(type default)
			)
			(fill yes)
			(layer "F.Fab")
		)
		(pad "1" smd rect
			(at -0.94996 -0.649986 90)
			(size 0.4318 0.508)
			(layers "F.Cu" "F.Mask" "F.Paste")
			(net "GND")
		)
		(pad "2" smd rect
			(at -0.94996 0 90)
			(size 0.4318 0.508)
			(layers "F.Cu" "F.Mask" "F.Paste")
			(net "RST_BMC_FROM_SWB_N")
		)
		(pad "3" smd rect
			(at -0.94996 0.649986 90)
			(size 0.4318 0.508)
			(layers "F.Cu" "F.Mask" "F.Paste")
			(net "RST_BMC_FROM_SWB_ISO_N")
		)
		(pad "4" smd rect
			(at 0.94996 0.649986 90)
			(size 0.4318 0.508)
			(layers "F.Cu" "F.Mask" "F.Paste")
			(net "GND")
		)
		(pad "5" smd rect
			(at 0.94996 0 90)
			(size 0.4318 0.508)
			(layers "F.Cu" "F.Mask" "F.Paste")
			(net "RST_BMC_FROM_SWB")
		)
		(pad "6" smd rect
			(at 0.94996 -0.649986 90)
			(size 0.4318 0.508)
			(layers "F.Cu" "F.Mask" "F.Paste")
			(net "RST_BMC_FROM_SWB")
		)
	)
	(footprint ""
		(layer "F.Cu")
		(at 325.211186 -416.899344 -90)
		(property "Reference" "C6516"
			(at 0 0 270)
			(layer "F.SilkS")
			(hide yes)
			(effects
				(font
					(size 1.27 1.27)
				)
			)
		)
		(property "Value" ""
			(at 0 0 270)
			(layer "F.Fab")
			(effects
				(font
					(size 1.27 1.27)
				)
			)
		)
		(duplicate_pad_numbers_are_jumpers no)
		(fp_line
			(start -0.299974 0.150114)
			(end -0.299974 -0.150114)
			(stroke
				(width 0.1)
				(type default)
			)
			(layer "F.Fab")
		)
		(fp_line
			(start 0.299974 0.150114)
			(end -0.299974 0.150114)
			(stroke
				(width 0.1)
				(type default)
			)
			(layer "F.Fab")
		)
		(fp_line
			(start -0.299974 -0.150114)
			(end 0.299974 -0.150114)
			(stroke
				(width 0.1)
				(type default)
			)
			(layer "F.Fab")
		)
		(fp_line
			(start 0.299974 -0.150114)
			(end 0.299974 0.150114)
			(stroke
				(width 0.1)
				(type default)
			)
			(layer "F.Fab")
		)
		(pad "1" smd rect
			(at -0.2667 0 270)
			(size 0.3048 0.381)
			(layers "F.Cu" "F.Mask" "F.Paste")
			(net "P5E_CPU0_P0_TX_BUF_C_DN<7>")
		)
		(pad "2" smd rect
			(at 0.2667 0 270)
			(size 0.3048 0.381)
			(layers "F.Cu" "F.Mask" "F.Paste")
			(net "P5E_CPU0_P0_TX_BUF_DN<7>")
		)
	)
	(footprint ""
		(layer "F.Cu")
		(at 30.075378 -132.788914 -90)
		(property "Reference" "C1882"
			(at 0 0 270)
			(layer "F.SilkS")
			(hide yes)
			(effects
				(font
					(size 1.27 1.27)
				)
			)
		)
		(property "Value" ""
			(at 0 0 270)
			(layer "F.Fab")
			(effects
				(font
					(size 1.27 1.27)
				)
			)
		)
		(duplicate_pad_numbers_are_jumpers no)
		(fp_line
			(start -0.7874 0.4064)
			(end -0.7874 -0.4064)
			(stroke
				(width 0.1524)
				(type default)
			)
			(layer "F.SilkS")
		)
		(fp_line
			(start 0.7874 0.4064)
			(end -0.7874 0.4064)
			(stroke
				(width 0.1524)
				(type default)
			)
			(layer "F.SilkS")
		)
		(fp_line
			(start -0.7874 -0.4064)
			(end 0.7874 -0.4064)
			(stroke
				(width 0.1524)
				(type default)
			)
			(layer "F.SilkS")
		)
		(fp_line
			(start 0.7874 -0.4064)
			(end 0.7874 0.4064)
			(stroke
				(width 0.1524)
				(type default)
			)
			(layer "F.SilkS")
		)
		(fp_line
			(start -0.67945 0.3048)
			(end -0.67945 -0.305054)
			(stroke
				(width 0.1)
				(type default)
			)
			(layer "F.Fab")
		)
		(fp_line
			(start -0.12065 0.3048)
			(end -0.67945 0.3048)
			(stroke
				(width 0.1)
				(type default)
			)
			(layer "F.Fab")
		)
		(fp_line
			(start 0.120396 0.3048)
			(end 0.120396 0.2794)
			(stroke
				(width 0.1)
				(type default)
			)
			(layer "F.Fab")
		)
		(fp_line
			(start 0.67945 0.3048)
			(end 0.120396 0.3048)
			(stroke
				(width 0.1)
				(type default)
			)
			(layer "F.Fab")
		)
		(fp_line
			(start -0.12065 0.2794)
			(end -0.12065 0.3048)
			(stroke
				(width 0.1)
				(type default)
			)
			(layer "F.Fab")
		)
		(fp_line
			(start 0.120396 0.2794)
			(end -0.12065 0.2794)
			(stroke
				(width 0.1)
				(type default)
			)
			(layer "F.Fab")
		)
		(fp_line
			(start -0.12065 -0.2794)
			(end 0.12065 -0.2794)
			(stroke
				(width 0.1)
				(type default)
			)
			(layer "F.Fab")
		)
		(fp_line
			(start 0.12065 -0.2794)
			(end 0.12065 -0.3048)
			(stroke
				(width 0.1)
				(type default)
			)
			(layer "F.Fab")
		)
		(fp_line
			(start 0.12065 -0.3048)
			(end 0.67945 -0.3048)
			(stroke
				(width 0.1)
				(type default)
			)
			(layer "F.Fab")
		)
		(fp_line
			(start 0.67945 -0.3048)
			(end 0.67945 0.3048)
			(stroke
				(width 0.1)
				(type default)
			)
			(layer "F.Fab")
		)
		(fp_line
			(start -0.67945 -0.305054)
			(end -0.12065 -0.305054)
			(stroke
				(width 0.1)
				(type default)
			)
			(layer "F.Fab")
		)
		(fp_line
			(start -0.12065 -0.305054)
			(end -0.12065 -0.2794)
			(stroke
				(width 0.1)
				(type default)
			)
			(layer "F.Fab")
		)
		(pad "1" smd circle
			(at -0.40005 0 270)
			(size 0 0)
			(layers "F.Cu" "F.Mask" "F.Paste")
			(net "P3V3_AUX")
		)
		(pad "2" smd circle
			(at 0.40005 0 270)
			(size 0 0)
			(layers "F.Cu" "F.Mask" "F.Paste")
			(net "GND")
		)
	)
)
